(kicad_pcb
	(version 20260206)
	(generator "pcbnew")
	(generator_version "10.0")
	(general
		(thickness 1.6)
		(legacy_teardrops no)
	)
	(paper "A4")
	(title_block
		(title "baseboard — 13948-1b.1110WZS1818.brd")
		(comment 1 "Honey Badger (Wiwynn) / footprints 1335-1341 of 2523")
	)
	(layers
		(0 "F.Cu" signal "TOP")
		(4 "In1.Cu" signal "L2GND")
		(6 "In2.Cu" signal "L3")
		(8 "In3.Cu" signal "L4VCC")
		(10 "In4.Cu" signal "L5VCC")
		(12 "In5.Cu" signal "L6")
		(14 "In6.Cu" signal "L7GND")
		(2 "B.Cu" signal "BOTTOM")
		(9 "F.Adhes" user "F.Adhesive")
		(11 "B.Adhes" user "B.Adhesive")
		(13 "F.Paste" user "Package Geometry/Pastemask Top")
		(15 "B.Paste" user "Package Geometry/Pastemask Bottom")
		(5 "F.SilkS" user "Ref Des/Silkscreen Top")
		(7 "B.SilkS" user "Ref Des/Silkscreen Bottom")
		(1 "F.Mask" user "Board Geometry/Soldermask Top")
		(3 "B.Mask" user "Board Geometry/Soldermask Bottom")
		(17 "Dwgs.User" user "User.Drawings")
		(19 "Cmts.User" user "User.Comments")
		(21 "Eco1.User" user "User.Eco1")
		(23 "Eco2.User" user "User.Eco2")
		(25 "Edge.Cuts" user "Board Geometry/Outline")
		(27 "Margin" user)
		(31 "F.CrtYd" user "Package Geometry/Place Bound Top")
		(29 "B.CrtYd" user "Package Geometry/Place Bound Bottom")
		(35 "F.Fab" user "Ref Des/Assembly Top")
		(33 "B.Fab" user "Ref Des/Assembly Bottom")
	)
	(footprint ""
		(layer "F.Cu")
		(at 111.89716 -26.924 -90)
		(property "Reference" "SR685"
			(at 0 0 270)
			(layer "F.SilkS")
			(hide yes)
			(effects
				(font
					(size 1.27 1.27)
				)
			)
		)
		(property "Value" "10KR2F-2-GP"
			(at 0.064008 -3.993896 270)
			(unlocked yes)
			(layer "F.Fab")
			(hide yes)
			(effects
				(font
					(size 1.016 1.016)
					(thickness 0.1524)
				)
			)
		)
		(property "Device Type" "R402H16"
			(at 0.064008 -5.517896 270)
			(unlocked yes)
			(layer "F.Fab")
			(hide yes)
			(effects
				(font
					(size 1.016 1.016)
					(thickness 0.1524)
				)
			)
		)
		(duplicate_pad_numbers_are_jumpers no)
		(fp_line
			(start -0.508 -0.9398)
			(end -0.508 0.9398)
			(stroke
				(width 0.1524)
				(type default)
			)
			(layer "F.SilkS")
		)
		(fp_line
			(start 0.508 -0.9398)
			(end -0.508 -0.9398)
			(stroke
				(width 0.1524)
				(type default)
			)
			(layer "F.SilkS")
		)
		(fp_rect
			(start -0.508 0.9398)
			(end 0.508 -0.9398)
			(stroke
				(width 0)
				(type default)
			)
			(fill no)
			(layer "F.CrtYd")
		)
		(fp_rect
			(start -0.508 0.9398)
			(end 0.508 -0.9398)
			(stroke
				(width 0)
				(type default)
			)
			(fill no)
			(layer "F.Fab")
		)
		(pad "1" smd custom
			(at 0 -0.4445 270)
			(size 0.1397 0.1397)
			(layers "F.Cu" "F.Mask" "F.Paste")
			(net "SYS_DBMODE1")
			(options
				(clearance outline)
				(anchor circle)
			)
			(primitives
				(gr_poly
					(pts
						(arc
							(start -0.1778 -0.2794)
							(mid -0.249642 -0.249642)
							(end -0.2794 -0.1778)
						)
						(arc
							(start -0.2794 0.1778)
							(mid -0.249642 0.249642)
							(end -0.1778 0.2794)
						)
						(arc
							(start 0.1778 0.2794)
							(mid 0.249642 0.249642)
							(end 0.2794 0.1778)
						)
						(arc
							(start 0.2794 -0.1778)
							(mid 0.249642 -0.249642)
							(end 0.1778 -0.2794)
						)
					)
					(width 0)
					(fill yes)
				)
			)
		)
		(pad "2" smd custom
			(at 0 0.4445 270)
			(size 0.1397 0.1397)
			(layers "F.Cu" "F.Mask" "F.Paste")
			(net "GND")
			(options
				(clearance outline)
				(anchor circle)
			)
			(primitives
				(gr_poly
					(pts
						(arc
							(start -0.1778 -0.2794)
							(mid -0.249642 -0.249642)
							(end -0.2794 -0.1778)
						)
						(arc
							(start -0.2794 0.1778)
							(mid -0.249642 0.249642)
							(end -0.1778 0.2794)
						)
						(arc
							(start 0.1778 0.2794)
							(mid 0.249642 0.249642)
							(end 0.2794 0.1778)
						)
						(arc
							(start 0.2794 -0.1778)
							(mid 0.249642 -0.249642)
							(end 0.1778 -0.2794)
						)
					)
					(width 0)
					(fill yes)
				)
			)
		)
	)
	(footprint ""
		(layer "F.Cu")
		(at 107.931966 -65.8876)
		(property "Reference" "SR658"
			(at 0 0 0)
			(layer "F.SilkS")
			(hide yes)
			(effects
				(font
					(size 1.27 1.27)
				)
			)
		)
		(property "Value" "4K7R2F-GP"
			(at 0.064008 -3.993896 0)
			(unlocked yes)
			(layer "F.Fab")
			(hide yes)
			(effects
				(font
					(size 1.016 1.016)
					(thickness 0.1524)
				)
			)
		)
		(property "Device Type" "R402H16"
			(at 0.064008 -5.517896 0)
			(unlocked yes)
			(layer "F.Fab")
			(hide yes)
			(effects
				(font
					(size 1.016 1.016)
					(thickness 0.1524)
				)
			)
		)
		(duplicate_pad_numbers_are_jumpers no)
		(fp_line
			(start -0.508 -0.9398)
			(end -0.508 0.9398)
			(stroke
				(width 0.1524)
				(type default)
			)
			(layer "F.SilkS")
		)
		(fp_line
			(start 0.508 -0.9398)
			(end -0.508 -0.9398)
			(stroke
				(width 0.1524)
				(type default)
			)
			(layer "F.SilkS")
		)
		(fp_rect
			(start -0.508 0.9398)
			(end 0.508 -0.9398)
			(stroke
				(width 0)
				(type default)
			)
			(fill no)
			(layer "F.CrtYd")
		)
		(fp_rect
			(start -0.508 0.9398)
			(end 0.508 -0.9398)
			(stroke
				(width 0)
				(type default)
			)
			(fill no)
			(layer "F.Fab")
		)
		(pad "1" smd custom
			(at 0 -0.4445)
			(size 0.1397 0.1397)
			(layers "F.Cu" "F.Mask" "F.Paste")
			(net "P1V8_C")
			(options
				(clearance outline)
				(anchor circle)
			)
			(primitives
				(gr_poly
					(pts
						(arc
							(start -0.1778 -0.2794)
							(mid -0.249642 -0.249642)
							(end -0.2794 -0.1778)
						)
						(arc
							(start -0.2794 0.1778)
							(mid -0.249642 0.249642)
							(end -0.1778 0.2794)
						)
						(arc
							(start 0.1778 0.2794)
							(mid 0.249642 0.249642)
							(end 0.2794 0.1778)
						)
						(arc
							(start 0.2794 -0.1778)
							(mid 0.249642 -0.249642)
							(end 0.1778 -0.2794)
						)
					)
					(width 0)
					(fill yes)
				)
			)
		)
		(pad "2" smd custom
			(at 0 0.4445)
			(size 0.1397 0.1397)
			(layers "F.Cu" "F.Mask" "F.Paste")
			(net "LSI_SCAN_EN")
			(options
				(clearance outline)
				(anchor circle)
			)
			(primitives
				(gr_poly
					(pts
						(arc
							(start -0.1778 -0.2794)
							(mid -0.249642 -0.249642)
							(end -0.2794 -0.1778)
						)
						(arc
							(start -0.2794 0.1778)
							(mid -0.249642 0.249642)
							(end -0.1778 0.2794)
						)
						(arc
							(start 0.1778 0.2794)
							(mid 0.249642 0.249642)
							(end 0.2794 0.1778)
						)
						(arc
							(start 0.2794 -0.1778)
							(mid 0.249642 -0.249642)
							(end 0.1778 -0.2794)
						)
					)
					(width 0)
					(fill yes)
				)
			)
		)
	)
	(footprint ""
		(layer "F.Cu")
		(at 140.47597 -83.566 180)
		(property "Reference" "R167"
			(at 0 0 180)
			(layer "F.SilkS")
			(hide yes)
			(effects
				(font
					(size 1.27 1.27)
				)
			)
		)
		(property "Value" "4K7R2F-GP"
			(at 0.064008 -3.993896 180)
			(unlocked yes)
			(layer "F.Fab")
			(hide yes)
			(effects
				(font
					(size 1.016 1.016)
					(thickness 0.1524)
				)
			)
		)
		(property "Device Type" "R402H16"
			(at 0.064008 -5.517896 180)
			(unlocked yes)
			(layer "F.Fab")
			(hide yes)
			(effects
				(font
					(size 1.016 1.016)
					(thickness 0.1524)
				)
			)
		)
		(duplicate_pad_numbers_are_jumpers no)
		(fp_line
			(start 0.508 -0.9398)
			(end -0.508 -0.9398)
			(stroke
				(width 0.1524)
				(type default)
			)
			(layer "F.SilkS")
		)
		(fp_line
			(start -0.508 -0.9398)
			(end -0.508 0.9398)
			(stroke
				(width 0.1524)
				(type default)
			)
			(layer "F.SilkS")
		)
		(fp_rect
			(start -0.508 0.9398)
			(end 0.508 -0.9398)
			(stroke
				(width 0)
				(type default)
			)
			(fill no)
			(layer "F.CrtYd")
		)
		(fp_rect
			(start -0.508 0.9398)
			(end 0.508 -0.9398)
			(stroke
				(width 0)
				(type default)
			)
			(fill no)
			(layer "F.Fab")
		)
		(pad "1" smd custom
			(at 0 -0.4445 180)
			(size 0.1397 0.1397)
			(layers "F.Cu" "F.Mask" "F.Paste")
			(net "P3V3_STBY")
			(options
				(clearance outline)
				(anchor circle)
			)
			(primitives
				(gr_poly
					(pts
						(arc
							(start -0.1778 -0.2794)
							(mid -0.249642 -0.249642)
							(end -0.2794 -0.1778)
						)
						(arc
							(start -0.2794 0.1778)
							(mid -0.249642 0.249642)
							(end -0.1778 0.2794)
						)
						(arc
							(start 0.1778 0.2794)
							(mid 0.249642 0.249642)
							(end 0.2794 0.1778)
						)
						(arc
							(start 0.2794 -0.1778)
							(mid 0.249642 -0.249642)
							(end 0.1778 -0.2794)
						)
					)
					(width 0)
					(fill yes)
				)
			)
		)
		(pad "2" smd custom
			(at 0 0.4445 180)
			(size 0.1397 0.1397)
			(layers "F.Cu" "F.Mask" "F.Paste")
			(net "TEMP_3_A1")
			(options
				(clearance outline)
				(anchor circle)
			)
			(primitives
				(gr_poly
					(pts
						(arc
							(start -0.1778 -0.2794)
							(mid -0.249642 -0.249642)
							(end -0.2794 -0.1778)
						)
						(arc
							(start -0.2794 0.1778)
							(mid -0.249642 0.249642)
							(end -0.1778 0.2794)
						)
						(arc
							(start 0.1778 0.2794)
							(mid 0.249642 0.249642)
							(end 0.2794 0.1778)
						)
						(arc
							(start 0.2794 -0.1778)
							(mid 0.249642 -0.249642)
							(end 0.1778 -0.2794)
						)
					)
					(width 0)
					(fill yes)
				)
			)
		)
	)
	(footprint ""
		(layer "F.Cu")
		(at 110.37316 -27.432)
		(property "Reference" "SR687"
			(at 0 0 0)
			(layer "F.SilkS")
			(hide yes)
			(effects
				(font
					(size 1.27 1.27)
				)
			)
		)
		(property "Value" "10KR2F-2-GP"
			(at 0.064008 -3.993896 0)
			(unlocked yes)
			(layer "F.Fab")
			(hide yes)
			(effects
				(font
					(size 1.016 1.016)
					(thickness 0.1524)
				)
			)
		)
		(property "Device Type" "R402H16"
			(at 0.064008 -5.517896 0)
			(unlocked yes)
			(layer "F.Fab")
			(hide yes)
			(effects
				(font
					(size 1.016 1.016)
					(thickness 0.1524)
				)
			)
		)
		(duplicate_pad_numbers_are_jumpers no)
		(fp_line
			(start -0.508 -0.9398)
			(end -0.508 0.9398)
			(stroke
				(width 0.1524)
				(type default)
			)
			(layer "F.SilkS")
		)
		(fp_line
			(start 0.508 -0.9398)
			(end -0.508 -0.9398)
			(stroke
				(width 0.1524)
				(type default)
			)
			(layer "F.SilkS")
		)
		(fp_rect
			(start -0.508 0.9398)
			(end 0.508 -0.9398)
			(stroke
				(width 0)
				(type default)
			)
			(fill no)
			(layer "F.CrtYd")
		)
		(fp_rect
			(start -0.508 0.9398)
			(end 0.508 -0.9398)
			(stroke
				(width 0)
				(type default)
			)
			(fill no)
			(layer "F.Fab")
		)
		(pad "1" smd custom
			(at 0 -0.4445)
			(size 0.1397 0.1397)
			(layers "F.Cu" "F.Mask" "F.Paste")
			(net "SYS_DBMODE4")
			(options
				(clearance outline)
				(anchor circle)
			)
			(primitives
				(gr_poly
					(pts
						(arc
							(start -0.1778 -0.2794)
							(mid -0.249642 -0.249642)
							(end -0.2794 -0.1778)
						)
						(arc
							(start -0.2794 0.1778)
							(mid -0.249642 0.249642)
							(end -0.1778 0.2794)
						)
						(arc
							(start 0.1778 0.2794)
							(mid 0.249642 0.249642)
							(end 0.2794 0.1778)
						)
						(arc
							(start 0.2794 -0.1778)
							(mid 0.249642 -0.249642)
							(end 0.1778 -0.2794)
						)
					)
					(width 0)
					(fill yes)
				)
			)
		)
		(pad "2" smd custom
			(at 0 0.4445)
			(size 0.1397 0.1397)
			(layers "F.Cu" "F.Mask" "F.Paste")
			(net "GND")
			(options
				(clearance outline)
				(anchor circle)
			)
			(primitives
				(gr_poly
					(pts
						(arc
							(start -0.1778 -0.2794)
							(mid -0.249642 -0.249642)
							(end -0.2794 -0.1778)
						)
						(arc
							(start -0.2794 0.1778)
							(mid -0.249642 0.249642)
							(end -0.1778 0.2794)
						)
						(arc
							(start 0.1778 0.2794)
							(mid 0.249642 0.249642)
							(end 0.2794 0.1778)
						)
						(arc
							(start 0.2794 -0.1778)
							(mid 0.249642 -0.249642)
							(end 0.1778 -0.2794)
						)
					)
					(width 0)
					(fill yes)
				)
			)
		)
	)
	(footprint ""
		(layer "F.Cu")
		(at 90.297 -231.775 180)
		(property "Reference" "R619"
			(at 0 0 180)
			(layer "F.SilkS")
			(hide yes)
			(effects
				(font
					(size 1.27 1.27)
				)
			)
		)
		(property "Value" "0R2J-2-GP"
			(at 0.064008 -3.993896 180)
			(unlocked yes)
			(layer "F.Fab")
			(hide yes)
			(effects
				(font
					(size 1.016 1.016)
					(thickness 0.1524)
				)
			)
		)
		(property "Device Type" "R402H16"
			(at 0.064008 -5.517896 180)
			(unlocked yes)
			(layer "F.Fab")
			(hide yes)
			(effects
				(font
					(size 1.016 1.016)
					(thickness 0.1524)
				)
			)
		)
		(duplicate_pad_numbers_are_jumpers no)
		(fp_line
			(start 0.508 -0.9398)
			(end -0.508 -0.9398)
			(stroke
				(width 0.1524)
				(type default)
			)
			(layer "F.SilkS")
		)
		(fp_line
			(start -0.508 -0.9398)
			(end -0.508 0.9398)
			(stroke
				(width 0.1524)
				(type default)
			)
			(layer "F.SilkS")
		)
		(fp_rect
			(start -0.508 0.9398)
			(end 0.508 -0.9398)
			(stroke
				(width 0)
				(type default)
			)
			(fill no)
			(layer "F.CrtYd")
		)
		(fp_rect
			(start -0.508 0.9398)
			(end 0.508 -0.9398)
			(stroke
				(width 0)
				(type default)
			)
			(fill no)
			(layer "F.Fab")
		)
		(pad "1" smd custom
			(at 0 -0.4445 180)
			(size 0.1397 0.1397)
			(layers "F.Cu" "F.Mask" "F.Paste")
			(net "SAS_FAULT_LED14")
			(options
				(clearance outline)
				(anchor circle)
			)
			(primitives
				(gr_poly
					(pts
						(arc
							(start -0.1778 -0.2794)
							(mid -0.249642 -0.249642)
							(end -0.2794 -0.1778)
						)
						(arc
							(start -0.2794 0.1778)
							(mid -0.249642 0.249642)
							(end -0.1778 0.2794)
						)
						(arc
							(start 0.1778 0.2794)
							(mid 0.249642 0.249642)
							(end 0.2794 0.1778)
						)
						(arc
							(start 0.2794 -0.1778)
							(mid 0.249642 -0.249642)
							(end 0.1778 -0.2794)
						)
					)
					(width 0)
					(fill yes)
				)
			)
		)
		(pad "2" smd custom
			(at 0 0.4445 180)
			(size 0.1397 0.1397)
			(layers "F.Cu" "F.Mask" "F.Paste")
			(net "SAS_HDD_LED_14")
			(options
				(clearance outline)
				(anchor circle)
			)
			(primitives
				(gr_poly
					(pts
						(arc
							(start -0.1778 -0.2794)
							(mid -0.249642 -0.249642)
							(end -0.2794 -0.1778)
						)
						(arc
							(start -0.2794 0.1778)
							(mid -0.249642 0.249642)
							(end -0.1778 0.2794)
						)
						(arc
							(start 0.1778 0.2794)
							(mid 0.249642 0.249642)
							(end 0.2794 0.1778)
						)
						(arc
							(start 0.2794 -0.1778)
							(mid 0.249642 -0.249642)
							(end 0.1778 -0.2794)
						)
					)
					(width 0)
					(fill yes)
				)
			)
		)
	)
	(footprint ""
		(layer "F.Cu")
		(at 139.446 -38.862)
		(property "Reference" "SR702"
			(at 0 0 0)
			(layer "F.SilkS")
			(hide yes)
			(effects
				(font
					(size 1.27 1.27)
				)
			)
		)
		(property "Value" "10KR2F-2-GP"
			(at 0.064008 -3.993896 0)
			(unlocked yes)
			(layer "F.Fab")
			(hide yes)
			(effects
				(font
					(size 1.016 1.016)
					(thickness 0.1524)
				)
			)
		)
		(property "Device Type" "R402H16"
			(at 0.064008 -5.517896 0)
			(unlocked yes)
			(layer "F.Fab")
			(hide yes)
			(effects
				(font
					(size 1.016 1.016)
					(thickness 0.1524)
				)
			)
		)
		(duplicate_pad_numbers_are_jumpers no)
		(fp_line
			(start -0.508 -0.9398)
			(end -0.508 0.9398)
			(stroke
				(width 0.1524)
				(type default)
			)
			(layer "F.SilkS")
		)
		(fp_line
			(start 0.508 -0.9398)
			(end -0.508 -0.9398)
			(stroke
				(width 0.1524)
				(type default)
			)
			(layer "F.SilkS")
		)
		(fp_rect
			(start -0.508 0.9398)
			(end 0.508 -0.9398)
			(stroke
				(width 0)
				(type default)
			)
			(fill no)
			(layer "F.CrtYd")
		)
		(fp_rect
			(start -0.508 0.9398)
			(end 0.508 -0.9398)
			(stroke
				(width 0)
				(type default)
			)
			(fill no)
			(layer "F.Fab")
		)
		(pad "1" smd custom
			(at 0 -0.4445)
			(size 0.1397 0.1397)
			(layers "F.Cu" "F.Mask" "F.Paste")
			(net "XM_ADDR_11")
			(options
				(clearance outline)
				(anchor circle)
			)
			(primitives
				(gr_poly
					(pts
						(arc
							(start -0.1778 -0.2794)
							(mid -0.249642 -0.249642)
							(end -0.2794 -0.1778)
						)
						(arc
							(start -0.2794 0.1778)
							(mid -0.249642 0.249642)
							(end -0.1778 0.2794)
						)
						(arc
							(start 0.1778 0.2794)
							(mid 0.249642 0.249642)
							(end 0.2794 0.1778)
						)
						(arc
							(start 0.2794 -0.1778)
							(mid 0.249642 -0.249642)
							(end 0.1778 -0.2794)
						)
					)
					(width 0)
					(fill yes)
				)
			)
		)
		(pad "2" smd custom
			(at 0 0.4445)
			(size 0.1397 0.1397)
			(layers "F.Cu" "F.Mask" "F.Paste")
			(net "GND")
			(options
				(clearance outline)
				(anchor circle)
			)
			(primitives
				(gr_poly
					(pts
						(arc
							(start -0.1778 -0.2794)
							(mid -0.249642 -0.249642)
							(end -0.2794 -0.1778)
						)
						(arc
							(start -0.2794 0.1778)
							(mid -0.249642 0.249642)
							(end -0.1778 0.2794)
						)
						(arc
							(start 0.1778 0.2794)
							(mid 0.249642 0.249642)
							(end 0.2794 0.1778)
						)
						(arc
							(start 0.2794 -0.1778)
							(mid 0.249642 -0.249642)
							(end 0.1778 -0.2794)
						)
					)
					(width 0)
					(fill yes)
				)
			)
		)
	)
	(footprint ""
		(layer "F.Cu")
		(at 345.567 -26.924 -90)
		(property "Reference" "R454"
			(at 0 0 270)
			(layer "F.SilkS")
			(hide yes)
			(effects
				(font
					(size 1.27 1.27)
				)
			)
		)
		(property "Value" "0R2J-2-GP"
			(at 0.064008 -3.993896 270)
			(unlocked yes)
			(layer "F.Fab")
			(hide yes)
			(effects
				(font
					(size 1.016 1.016)
					(thickness 0.1524)
				)
			)
		)
		(property "Device Type" "R402H16"
			(at 0.064008 -5.517896 270)
			(unlocked yes)
			(layer "F.Fab")
			(hide yes)
			(effects
				(font
					(size 1.016 1.016)
					(thickness 0.1524)
				)
			)
		)
		(duplicate_pad_numbers_are_jumpers no)
		(fp_line
			(start -0.508 -0.9398)
			(end -0.508 0.9398)
			(stroke
				(width 0.1524)
				(type default)
			)
			(layer "F.SilkS")
		)
		(fp_line
			(start 0.508 -0.9398)
			(end -0.508 -0.9398)
			(stroke
				(width 0.1524)
				(type default)
			)
			(layer "F.SilkS")
		)
		(fp_rect
			(start -0.508 0.9398)
			(end 0.508 -0.9398)
			(stroke
				(width 0)
				(type default)
			)
			(fill no)
			(layer "F.CrtYd")
		)
		(fp_rect
			(start -0.508 0.9398)
			(end 0.508 -0.9398)
			(stroke
				(width 0)
				(type default)
			)
			(fill no)
			(layer "F.Fab")
		)
		(pad "1" smd custom
			(at 0 -0.4445 270)
			(size 0.1397 0.1397)
			(layers "F.Cu" "F.Mask" "F.Paste")
			(net "BMC_UART_SWITCH_1")
			(options
				(clearance outline)
				(anchor circle)
			)
			(primitives
				(gr_poly
					(pts
						(arc
							(start -0.1778 -0.2794)
							(mid -0.249642 -0.249642)
							(end -0.2794 -0.1778)
						)
						(arc
							(start -0.2794 0.1778)
							(mid -0.249642 0.249642)
							(end -0.1778 0.2794)
						)
						(arc
							(start 0.1778 0.2794)
							(mid 0.249642 0.249642)
							(end 0.2794 0.1778)
						)
						(arc
							(start 0.2794 -0.1778)
							(mid 0.249642 -0.249642)
							(end 0.1778 -0.2794)
						)
					)
					(width 0)
					(fill yes)
				)
			)
		)
		(pad "2" smd custom
			(at 0 0.4445 270)
			(size 0.1397 0.1397)
			(layers "F.Cu" "F.Mask" "F.Paste")
			(net "BMC_CONSOLE_LED0_R")
			(options
				(clearance outline)
				(anchor circle)
			)
			(primitives
				(gr_poly
					(pts
						(arc
							(start -0.1778 -0.2794)
							(mid -0.249642 -0.249642)
							(end -0.2794 -0.1778)
						)
						(arc
							(start -0.2794 0.1778)
							(mid -0.249642 0.249642)
							(end -0.1778 0.2794)
						)
						(arc
							(start 0.1778 0.2794)
							(mid 0.249642 0.249642)
							(end 0.2794 0.1778)
						)
						(arc
							(start 0.2794 -0.1778)
							(mid 0.249642 -0.249642)
							(end 0.1778 -0.2794)
						)
					)
					(width 0)
					(fill yes)
				)
			)
		)
	)
)
